# BASEBOARD_FAB2 (Tioga Pass) — schematic netlist excerpt (pin names and nets, part order shuffled) for the footprints in the layout excerpt that follows; sources: Cadence DE-HDL packaged netlist, KiCad conversion of Wiwynn_Tioga_Pass_MB.brd

R4W4  RES  3.3K 5% CHIP  pkg 0402  page 102 : A = P3V3_DB1200 ; B = SMB_HOST_STBY_LVC3_SCL_R2
C25W4  CAP  1.0UF 16V 10% X6S  pkg 0402  page 151 : A = P1V2_AUX_BMC ; B = GND
R1D53  RES  2.26K 1.0% EMPTY  pkg 0402  page 206 : A = P3V3_STBY ; B = PU_VR_PVCCIN_CPU1_FLT1_SMBALT_N

(kicad_pcb
	(version 20260206)
	(generator "pcbnew")
	(generator_version "10.0")
	(general
		(thickness 1.6)
		(legacy_teardrops no)
	)
	(paper "A4")
	(title_block
		(title "Wiwynn_Tioga_Pass_MB.brd")
		(comment 1 "Tioga Pass / footprints 1960-1962 of 4770")
	)
	(layers
		(0 "F.Cu" signal "TOP")
		(4 "In1.Cu" signal "L2GND")
		(6 "In2.Cu" signal "L3")
		(8 "In3.Cu" signal "L4GND")
		(10 "In4.Cu" signal "L5")
		(12 "In5.Cu" signal "L6GND")
		(14 "In6.Cu" signal "L7VCC")
		(16 "In7.Cu" signal "L8VCC")
		(18 "In8.Cu" signal "L9GND")
		(20 "In9.Cu" signal "L10")
		(22 "In10.Cu" signal "L11GND")
		(24 "In11.Cu" signal "L12")
		(26 "In12.Cu" signal "L13GND")
		(2 "B.Cu" signal "BOTTOM")
		(9 "F.Adhes" user "F.Adhesive")
		(11 "B.Adhes" user "B.Adhesive")
		(13 "F.Paste" user "Package Geometry/Pastemask Top")
		(15 "B.Paste" user "Package Geometry/Pastemask Bottom")
		(5 "F.SilkS" user "Ref Des/Silkscreen Top")
		(7 "B.SilkS" user "Ref Des/Silkscreen Bottom")
		(1 "F.Mask" user "Board Geometry/Soldermask Top")
		(3 "B.Mask" user "Board Geometry/Soldermask Bottom")
		(17 "Dwgs.User" user "User.Drawings")
		(19 "Cmts.User" user "User.Comments")
		(21 "Eco1.User" user "User.Eco1")
		(23 "Eco2.User" user "User.Eco2")
		(25 "Edge.Cuts" user "Board Geometry/Outline")
		(27 "Margin" user)
		(31 "F.CrtYd" user "Package Geometry/Place Bound Top")
		(29 "B.CrtYd" user "Package Geometry/Place Bound Bottom")
		(35 "F.Fab" user "Ref Des/Assembly Top")
		(33 "B.Fab" user "Ref Des/Assembly Bottom")
	)
	(footprint ""
		(layer "F.Cu")
		(at 450.521832 -28.772104)
		(property "Reference" "C25W4"
			(at -0.8382 -0.67818 0)
			(unlocked yes)
			(layer "F.SilkS")
			(effects
				(font
					(size 0.4064 0.254)
					(thickness 0.1524)
				)
				(justify left)
			)
		)
		(property "Value" ""
			(at 0 0 0)
			(layer "F.Fab")
			(effects
				(font
					(size 1.27 1.27)
				)
			)
		)
		(duplicate_pad_numbers_are_jumpers no)
		(fp_poly
			(pts
				(xy 0.3048 -0.1016) (xy 0.3048 0.9906) (xy -0.3048 0.9906) (xy -0.3048 -0.1016)
			)
			(stroke
				(width 0)
				(type default)
			)
			(fill no)
			(layer "F.CrtYd")
		)
		(fp_line
			(start -0.3048 -0.1016)
			(end -0.3048 0.9906)
			(stroke
				(width 0.1)
				(type default)
			)
			(layer "F.Fab")
		)
		(fp_line
			(start -0.3048 0.9906)
			(end 0.3048 0.9906)
			(stroke
				(width 0.1)
				(type default)
			)
			(layer "F.Fab")
		)
		(fp_line
			(start 0.3048 -0.1016)
			(end -0.3048 -0.1016)
			(stroke
				(width 0.1)
				(type default)
			)
			(layer "F.Fab")
		)
		(fp_line
			(start 0.3048 0.9906)
			(end 0.3048 -0.1016)
			(stroke
				(width 0.1)
				(type default)
			)
			(layer "F.Fab")
		)
		(pad "1" smd rect
			(at 0 0)
			(size 0.508 0.508)
			(layers "F.Cu" "F.Mask" "F.Paste")
			(net "P1V2_AUX_BMC")
		)
		(pad "2" smd rect
			(at 0 0.889)
			(size 0.508 0.508)
			(layers "F.Cu" "F.Mask" "F.Paste")
			(net "GND")
		)
		(zone
			(layer "F.Cu")
			(hatch none 0.5)
			(connect_pads
				(clearance 0)
			)
			(min_thickness 0.25)
			(keepout
				(tracks allowed)
				(vias not_allowed)
				(pads allowed)
				(copperpour not_allowed)
				(footprints allowed)
			)
			(placement
				(enabled no)
				(sheetname "")
			)
			(fill
				(thermal_gap 0.5)
				(thermal_bridge_width 0.5)
				(island_removal_mode 0)
			)
			(polygon
				(pts
					(xy 450.267832 -28.518104) (xy 450.775832 -28.518104) (xy 450.775832 -28.137104) (xy 450.267832 -28.137104)
				)
			)
		)
		(zone
			(layer "F.Cu")
			(hatch none 0.5)
			(connect_pads
				(clearance 0)
			)
			(min_thickness 0.25)
			(keepout
				(tracks not_allowed)
				(vias allowed)
				(pads allowed)
				(copperpour not_allowed)
				(footprints allowed)
			)
			(placement
				(enabled no)
				(sheetname "")
			)
			(fill
				(thermal_gap 0.5)
				(thermal_bridge_width 0.5)
				(island_removal_mode 0)
			)
			(polygon
				(pts
					(xy 450.267832 -28.137104) (xy 450.775832 -28.137104) (xy 450.775832 -28.518104) (xy 450.267832 -28.518104)
				)
			)
		)
	)
	(footprint ""
		(layer "F.Cu")
		(at 174.639224 -75.004168 -90)
		(property "Reference" "R4W4"
			(at -0.8382 -0.67818 270)
			(unlocked yes)
			(layer "F.SilkS")
			(effects
				(font
					(size 0.4064 0.254)
					(thickness 0.1524)
				)
				(justify left)
			)
		)
		(property "Value" ""
			(at 0 0 270)
			(layer "F.Fab")
			(effects
				(font
					(size 1.27 1.27)
				)
			)
		)
		(duplicate_pad_numbers_are_jumpers no)
		(fp_poly
			(pts
				(xy -0.2794 -0.1016) (xy 0.2794 -0.1016) (xy 0.2794 0.9906) (xy -0.2794 0.9906)
			)
			(stroke
				(width 0)
				(type default)
			)
			(fill no)
			(layer "F.CrtYd")
		)
		(fp_line
			(start -0.2794 0.9906)
			(end 0.2794 0.9906)
			(stroke
				(width 0.1)
				(type default)
			)
			(layer "F.Fab")
		)
		(fp_line
			(start 0.2794 0.9906)
			(end 0.2794 -0.1016)
			(stroke
				(width 0.1)
				(type default)
			)
			(layer "F.Fab")
		)
		(fp_line
			(start -0.2794 -0.1016)
			(end -0.2794 0.9906)
			(stroke
				(width 0.1)
				(type default)
			)
			(layer "F.Fab")
		)
		(fp_line
			(start 0.2794 -0.1016)
			(end -0.2794 -0.1016)
			(stroke
				(width 0.1)
				(type default)
			)
			(layer "F.Fab")
		)
		(pad "1" smd rect
			(at 0 0 270)
			(size 0.508 0.508)
			(layers "F.Cu" "F.Mask" "F.Paste")
			(net "P3V3_DB1200")
		)
		(pad "2" smd rect
			(at 0 0.889 270)
			(size 0.508 0.508)
			(layers "F.Cu" "F.Mask" "F.Paste")
			(net "SMB_HOST_STBY_LVC3_SCL_R2")
		)
		(zone
			(layer "F.Cu")
			(hatch none 0.5)
			(connect_pads
				(clearance 0)
			)
			(min_thickness 0.25)
			(keepout
				(tracks not_allowed)
				(vias allowed)
				(pads allowed)
				(copperpour not_allowed)
				(footprints allowed)
			)
			(placement
				(enabled no)
				(sheetname "")
			)
			(fill
				(thermal_gap 0.5)
				(thermal_bridge_width 0.5)
				(island_removal_mode 0)
			)
			(polygon
				(pts
					(xy 174.004224 -75.258168) (xy 174.004224 -74.750168) (xy 174.385224 -74.750168) (xy 174.385224 -75.258168)
				)
			)
		)
		(zone
			(layer "F.Cu")
			(hatch none 0.5)
			(connect_pads
				(clearance 0)
			)
			(min_thickness 0.25)
			(keepout
				(tracks allowed)
				(vias not_allowed)
				(pads allowed)
				(copperpour not_allowed)
				(footprints allowed)
			)
			(placement
				(enabled no)
				(sheetname "")
			)
			(fill
				(thermal_gap 0.5)
				(thermal_bridge_width 0.5)
				(island_removal_mode 0)
			)
			(polygon
				(pts
					(xy 174.385224 -75.258168) (xy 174.385224 -74.750168) (xy 174.004224 -74.750168) (xy 174.004224 -75.258168)
				)
			)
		)
	)
	(footprint ""
		(layer "F.Cu")
		(at 19.812 -86.6267 180)
		(property "Reference" "R1D53"
			(at 0 0 180)
			(layer "F.SilkS")
			(hide yes)
			(effects
				(font
					(size 1.27 1.27)
				)
			)
		)
		(property "Value" ""
			(at 0 0 180)
			(layer "F.Fab")
			(effects
				(font
					(size 1.27 1.27)
				)
			)
		)
		(duplicate_pad_numbers_are_jumpers no)
		(fp_rect
			(start -0.2794 0.9906)
			(end 0.2794 -0.1016)
			(stroke
				(width 0)
				(type default)
			)
			(fill no)
			(layer "F.CrtYd")
		)
		(fp_line
			(start 0.2794 0.9906)
			(end 0.2794 -0.1016)
			(stroke
				(width 0.1)
				(type default)
			)
			(layer "F.Fab")
		)
		(fp_line
			(start 0.2794 -0.1016)
			(end -0.2794 -0.1016)
			(stroke
				(width 0.1)
				(type default)
			)
			(layer "F.Fab")
		)
		(fp_line
			(start -0.2794 0.9906)
			(end 0.2794 0.9906)
			(stroke
				(width 0.1)
				(type default)
			)
			(layer "F.Fab")
		)
		(fp_line
			(start -0.2794 -0.1016)
			(end -0.2794 0.9906)
			(stroke
				(width 0.1)
				(type default)
			)
			(layer "F.Fab")
		)
		(pad "1" smd rect
			(at 0 0 180)
			(size 0.508 0.508)
			(layers "F.Cu" "F.Mask" "F.Paste")
			(net "P3V3_STBY")
		)
		(pad "2" smd rect
			(at 0 0.889 180)
			(size 0.508 0.508)
			(layers "F.Cu" "F.Mask" "F.Paste")
			(net "PU_VR_PVCCIN_CPU1_FLT1_SMBALT_N")
		)
		(zone
			(layer "F.Cu")
			(hatch none 0.5)
			(connect_pads
				(clearance 0)
			)
			(min_thickness 0.25)
			(keepout
				(tracks allowed)
				(vias not_allowed)
				(pads allowed)
				(copperpour not_allowed)
				(footprints allowed)
			)
			(placement
				(enabled no)
				(sheetname "")
			)
			(fill
				(thermal_gap 0.5)
				(thermal_bridge_width 0.5)
				(island_removal_mode 0)
			)
			(polygon
				(pts
					(xy 20.066 -87.2617) (xy 19.558 -87.2617) (xy 19.558 -86.8807) (xy 20.066 -86.8807)
				)
			)
		)
		(zone
			(layer "F.Cu")
			(hatch none 0.5)
			(connect_pads
				(clearance 0)
			)
			(min_thickness 0.25)
			(keepout
				(tracks not_allowed)
				(vias allowed)
				(pads allowed)
				(copperpour not_allowed)
				(footprints allowed)
			)
			(placement
				(enabled no)
				(sheetname "")
			)
			(fill
				(thermal_gap 0.5)
				(thermal_bridge_width 0.5)
				(island_removal_mode 0)
			)
			(polygon
				(pts
					(xy 20.066 -87.2617) (xy 19.558 -87.2617) (xy 19.558 -86.8807) (xy 20.066 -86.8807)
				)
			)
		)
	)
)
